(kicad_pcb
	(version 20260206)
	(generator "pcbnew")
	(generator_version "10.0")
	(general
		(thickness 1.6)
		(legacy_teardrops no)
	)
	(paper "A4")
	(title_block
		(title "Bryce Canyon_F.DPB_16315-1-OCP.brd")
		(comment 1 "Bryce Canyon / footprints 1714-1720 of 2223")
	)
	(layers
		(0 "F.Cu" signal "TOP")
		(4 "In1.Cu" signal "L2GND")
		(6 "In2.Cu" signal "L3")
		(8 "In3.Cu" signal "L4GND")
		(10 "In4.Cu" signal "L5")
		(12 "In5.Cu" signal "L6VCC")
		(14 "In6.Cu" signal "L7VCC")
		(16 "In7.Cu" signal "L8")
		(18 "In8.Cu" signal "L9GND")
		(20 "In9.Cu" signal "L10")
		(22 "In10.Cu" signal "L11GND")
		(2 "B.Cu" signal "BOTTOM")
		(9 "F.Adhes" user "F.Adhesive")
		(11 "B.Adhes" user "B.Adhesive")
		(13 "F.Paste" user "Package Geometry/Pastemask Top")
		(15 "B.Paste" user "Package Geometry/Pastemask Bottom")
		(5 "F.SilkS" user "Ref Des/Silkscreen Top")
		(7 "B.SilkS" user "Ref Des/Silkscreen Bottom")
		(1 "F.Mask" user "Board Geometry/Soldermask Top")
		(3 "B.Mask" user "Board Geometry/Soldermask Bottom")
		(17 "Dwgs.User" user "User.Drawings")
		(19 "Cmts.User" user "User.Comments")
		(21 "Eco1.User" user "User.Eco1")
		(23 "Eco2.User" user "User.Eco2")
		(25 "Edge.Cuts" user "Board Geometry/Outline")
		(27 "Margin" user)
		(31 "F.CrtYd" user "Package Geometry/Place Bound Top")
		(29 "B.CrtYd" user "Package Geometry/Place Bound Bottom")
		(35 "F.Fab" user "Ref Des/Assembly Top")
		(33 "B.Fab" user "Ref Des/Assembly Bottom")
	)
	(footprint ""
		(layer "F.Cu")
		(at 255.993646 -261.326122 180)
		(property "Reference" "R431"
			(at 0 0 180)
			(layer "F.SilkS")
			(hide yes)
			(effects
				(font
					(size 1.27 1.27)
				)
			)
		)
		(property "Value" "1KR2F-3-GP"
			(at 0.064008 -3.993896 180)
			(unlocked yes)
			(layer "F.Fab")
			(hide yes)
			(effects
				(font
					(size 1.016 1.016)
					(thickness 0.1524)
				)
			)
		)
		(property "Device Type" "R402H16"
			(at 0.064008 -5.517896 180)
			(unlocked yes)
			(layer "F.Fab")
			(hide yes)
			(effects
				(font
					(size 1.016 1.016)
					(thickness 0.1524)
				)
			)
		)
		(duplicate_pad_numbers_are_jumpers no)
		(fp_line
			(start 0.508 -0.9398)
			(end -0.508 -0.9398)
			(stroke
				(width 0.1524)
				(type default)
			)
			(layer "F.SilkS")
		)
		(fp_line
			(start -0.508 -0.9398)
			(end -0.508 0.9398)
			(stroke
				(width 0.1524)
				(type default)
			)
			(layer "F.SilkS")
		)
		(fp_rect
			(start -0.508 0.9398)
			(end 0.508 -0.9398)
			(stroke
				(width 0)
				(type default)
			)
			(fill no)
			(layer "F.CrtYd")
		)
		(fp_rect
			(start -0.508 0.9398)
			(end 0.508 -0.9398)
			(stroke
				(width 0)
				(type default)
			)
			(fill no)
			(layer "F.Fab")
		)
		(pad "1" smd custom
			(at 0 -0.4445 180)
			(size 0.1397 0.1397)
			(layers "F.Cu" "F.Mask" "F.Paste")
			(net "P3V3_STBY_A")
			(options
				(clearance outline)
				(anchor circle)
			)
			(primitives
				(gr_poly
					(pts
						(arc
							(start -0.1778 -0.2794)
							(mid -0.249642 -0.249642)
							(end -0.2794 -0.1778)
						)
						(arc
							(start -0.2794 0.1778)
							(mid -0.249642 0.249642)
							(end -0.1778 0.2794)
						)
						(arc
							(start 0.1778 0.2794)
							(mid 0.249642 0.249642)
							(end 0.2794 0.1778)
						)
						(arc
							(start 0.2794 -0.1778)
							(mid 0.249642 -0.249642)
							(end 0.1778 -0.2794)
						)
					)
					(width 0)
					(fill yes)
				)
			)
		)
		(pad "2" smd custom
			(at 0 0.4445 180)
			(size 0.1397 0.1397)
			(layers "F.Cu" "F.Mask" "F.Paste")
			(net "I2C_DRIVE_A_INS_SCL")
			(options
				(clearance outline)
				(anchor circle)
			)
			(primitives
				(gr_poly
					(pts
						(arc
							(start -0.1778 -0.2794)
							(mid -0.249642 -0.249642)
							(end -0.2794 -0.1778)
						)
						(arc
							(start -0.2794 0.1778)
							(mid -0.249642 0.249642)
							(end -0.1778 0.2794)
						)
						(arc
							(start 0.1778 0.2794)
							(mid 0.249642 0.249642)
							(end 0.2794 0.1778)
						)
						(arc
							(start 0.2794 -0.1778)
							(mid 0.249642 -0.249642)
							(end 0.1778 -0.2794)
						)
					)
					(width 0)
					(fill yes)
				)
			)
		)
	)
	(footprint ""
		(layer "F.Cu")
		(at 447.952876 -248.43105 -90)
		(property "Reference" "R1250"
			(at 0 0 270)
			(layer "F.SilkS")
			(hide yes)
			(effects
				(font
					(size 1.27 1.27)
				)
			)
		)
		(property "Value" "3D01R5F-GP"
			(at 0 -8.9535 270)
			(unlocked yes)
			(layer "F.Fab")
			(hide yes)
			(effects
				(font
					(size 1.27 1.016)
					(thickness 0.1524)
				)
			)
		)
		(property "Device Type" "R805H24"
			(at 0 -10.6299 270)
			(unlocked yes)
			(layer "F.Fab")
			(hide yes)
			(effects
				(font
					(size 1.27 1.016)
					(thickness 0.1524)
				)
			)
		)
		(duplicate_pad_numbers_are_jumpers no)
		(fp_line
			(start -0.889 1.7018)
			(end 0.889 1.7018)
			(stroke
				(width 0.1524)
				(type default)
			)
			(layer "F.SilkS")
		)
		(fp_line
			(start 0.889 1.7018)
			(end 0.889 -0.508)
			(stroke
				(width 0.1524)
				(type default)
			)
			(layer "F.SilkS")
		)
		(fp_line
			(start -0.889 0.0762)
			(end -0.889 1.7018)
			(stroke
				(width 0.1524)
				(type default)
			)
			(layer "F.SilkS")
		)
		(fp_line
			(start -0.889 -1.7018)
			(end -0.889 0.2794)
			(stroke
				(width 0.1524)
				(type default)
			)
			(layer "F.SilkS")
		)
		(fp_line
			(start 0.889 -1.7018)
			(end 0.889 -0.381)
			(stroke
				(width 0.1524)
				(type default)
			)
			(layer "F.SilkS")
		)
		(fp_line
			(start 0.889 -1.7018)
			(end -0.889 -1.7018)
			(stroke
				(width 0.1524)
				(type default)
			)
			(layer "F.SilkS")
		)
		(fp_poly
			(pts
				(xy 0.9652 -1.778) (xy 0.9652 1.778) (xy -0.9652 1.778) (xy -0.9652 -1.778)
			)
			(stroke
				(width 0)
				(type default)
			)
			(fill no)
			(layer "F.CrtYd")
		)
		(fp_rect
			(start -0.9652 1.778)
			(end 0.9652 -1.778)
			(stroke
				(width 0)
				(type default)
			)
			(fill no)
			(layer "F.Fab")
		)
		(pad "1" smd rect
			(at 0 -0.9652 270)
			(size 1.397 1.143)
			(layers "F.Cu" "F.Mask" "F.Paste")
			(net "P5V_C_SNB")
		)
		(pad "2" smd rect
			(at 0 0.9652 270)
			(size 1.397 1.143)
			(layers "F.Cu" "F.Mask" "F.Paste")
			(net "GND")
		)
	)
	(footprint ""
		(layer "F.Cu")
		(at 239.649 -256.7178)
		(property "Reference" "C14"
			(at 0 0 0)
			(layer "F.SilkS")
			(hide yes)
			(effects
				(font
					(size 1.27 1.27)
				)
			)
		)
		(property "Value" "SCD1U16V2KX-3GP"
			(at 1.1811 -2.7051 0)
			(unlocked yes)
			(layer "F.Fab")
			(hide yes)
			(effects
				(font
					(size 1.016 1.016)
					(thickness 0.1524)
				)
			)
		)
		(property "Device Type" "C402H22"
			(at 1.1811 -4.2291 0)
			(unlocked yes)
			(layer "F.Fab")
			(hide yes)
			(effects
				(font
					(size 1.016 1.016)
					(thickness 0.1524)
				)
			)
		)
		(duplicate_pad_numbers_are_jumpers no)
		(fp_rect
			(start -0.4318 0.9525)
			(end 0.4318 -0.9525)
			(stroke
				(width 0)
				(type default)
			)
			(fill no)
			(layer "F.CrtYd")
		)
		(fp_rect
			(start -0.4318 0.9525)
			(end 0.4318 -0.9525)
			(stroke
				(width 0)
				(type default)
			)
			(fill no)
			(layer "F.Fab")
		)
		(pad "1" smd custom
			(at 0 -0.4445)
			(size 0.1524 0.1524)
			(layers "F.Cu" "F.Mask" "F.Paste")
			(net "P3V3_STBY_A")
			(options
				(clearance outline)
				(anchor circle)
			)
			(primitives
				(gr_poly
					(pts
						(arc
							(start 0.3048 -0.2032)
							(mid 0.275042 -0.275042)
							(end 0.2032 -0.3048)
						)
						(arc
							(start -0.2032 -0.3048)
							(mid -0.275042 -0.275042)
							(end -0.3048 -0.2032)
						)
						(arc
							(start -0.3048 0.2032)
							(mid -0.275042 0.275042)
							(end -0.2032 0.3048)
						)
						(arc
							(start 0.2032 0.3048)
							(mid 0.275042 0.275042)
							(end 0.3048 0.2032)
						)
					)
					(width 0)
					(fill yes)
				)
			)
		)
		(pad "2" smd custom
			(at 0 0.4445)
			(size 0.1524 0.1524)
			(layers "F.Cu" "F.Mask" "F.Paste")
			(net "GND")
			(options
				(clearance outline)
				(anchor circle)
			)
			(primitives
				(gr_poly
					(pts
						(arc
							(start 0.3048 -0.2032)
							(mid 0.275042 -0.275042)
							(end 0.2032 -0.3048)
						)
						(arc
							(start -0.2032 -0.3048)
							(mid -0.275042 -0.275042)
							(end -0.3048 -0.2032)
						)
						(arc
							(start -0.3048 0.2032)
							(mid -0.275042 0.275042)
							(end -0.2032 0.3048)
						)
						(arc
							(start 0.2032 0.3048)
							(mid 0.275042 0.275042)
							(end 0.3048 0.2032)
						)
					)
					(width 0)
					(fill yes)
				)
			)
		)
	)
	(footprint ""
		(layer "F.Cu")
		(at 51.943 -165.1 -90)
		(property "Reference" "R436"
			(at 0 0 270)
			(layer "F.SilkS")
			(hide yes)
			(effects
				(font
					(size 1.27 1.27)
				)
			)
		)
		(property "Value" "4K7R2J-2-GP"
			(at 0.064008 -3.993896 270)
			(unlocked yes)
			(layer "F.Fab")
			(hide yes)
			(effects
				(font
					(size 1.016 1.016)
					(thickness 0.1524)
				)
			)
		)
		(property "Device Type" "R402H16"
			(at 0.064008 -5.517896 270)
			(unlocked yes)
			(layer "F.Fab")
			(hide yes)
			(effects
				(font
					(size 1.016 1.016)
					(thickness 0.1524)
				)
			)
		)
		(duplicate_pad_numbers_are_jumpers no)
		(fp_line
			(start -0.508 -0.9398)
			(end -0.508 0.9398)
			(stroke
				(width 0.1524)
				(type default)
			)
			(layer "F.SilkS")
		)
		(fp_line
			(start 0.508 -0.9398)
			(end -0.508 -0.9398)
			(stroke
				(width 0.1524)
				(type default)
			)
			(layer "F.SilkS")
		)
		(fp_rect
			(start -0.508 0.9398)
			(end 0.508 -0.9398)
			(stroke
				(width 0)
				(type default)
			)
			(fill no)
			(layer "F.CrtYd")
		)
		(fp_rect
			(start -0.508 0.9398)
			(end 0.508 -0.9398)
			(stroke
				(width 0)
				(type default)
			)
			(fill no)
			(layer "F.Fab")
		)
		(pad "1" smd custom
			(at 0 -0.4445 270)
			(size 0.1397 0.1397)
			(layers "F.Cu" "F.Mask" "F.Paste")
			(net "P12V_A")
			(options
				(clearance outline)
				(anchor circle)
			)
			(primitives
				(gr_poly
					(pts
						(arc
							(start -0.1778 -0.2794)
							(mid -0.249642 -0.249642)
							(end -0.2794 -0.1778)
						)
						(arc
							(start -0.2794 0.1778)
							(mid -0.249642 0.249642)
							(end -0.1778 0.2794)
						)
						(arc
							(start 0.1778 0.2794)
							(mid 0.249642 0.249642)
							(end 0.2794 0.1778)
						)
						(arc
							(start 0.2794 -0.1778)
							(mid 0.249642 -0.249642)
							(end 0.1778 -0.2794)
						)
					)
					(width 0)
					(fill yes)
				)
			)
		)
		(pad "2" smd custom
			(at 0 0.4445 270)
			(size 0.1397 0.1397)
			(layers "F.Cu" "F.Mask" "F.Paste")
			(net "SW_HDD_P13")
			(options
				(clearance outline)
				(anchor circle)
			)
			(primitives
				(gr_poly
					(pts
						(arc
							(start -0.1778 -0.2794)
							(mid -0.249642 -0.249642)
							(end -0.2794 -0.1778)
						)
						(arc
							(start -0.2794 0.1778)
							(mid -0.249642 0.249642)
							(end -0.1778 0.2794)
						)
						(arc
							(start 0.1778 0.2794)
							(mid 0.249642 0.249642)
							(end 0.2794 0.1778)
						)
						(arc
							(start 0.2794 -0.1778)
							(mid 0.249642 -0.249642)
							(end 0.1778 -0.2794)
						)
					)
					(width 0)
					(fill yes)
				)
			)
		)
	)
	(footprint ""
		(layer "F.Cu")
		(at 277.4188 -284.7086)
		(property "Reference" "R116"
			(at 0 0 0)
			(layer "F.SilkS")
			(hide yes)
			(effects
				(font
					(size 1.27 1.27)
				)
			)
		)
		(property "Value" "4K7R2F-GP"
			(at 0.064008 -3.993896 0)
			(unlocked yes)
			(layer "F.Fab")
			(hide yes)
			(effects
				(font
					(size 1.016 1.016)
					(thickness 0.1524)
				)
			)
		)
		(property "Device Type" "R402H16"
			(at 0.064008 -5.517896 0)
			(unlocked yes)
			(layer "F.Fab")
			(hide yes)
			(effects
				(font
					(size 1.016 1.016)
					(thickness 0.1524)
				)
			)
		)
		(duplicate_pad_numbers_are_jumpers no)
		(fp_line
			(start -0.508 -0.9398)
			(end -0.508 0.9398)
			(stroke
				(width 0.1524)
				(type default)
			)
			(layer "F.SilkS")
		)
		(fp_line
			(start 0.508 -0.9398)
			(end -0.508 -0.9398)
			(stroke
				(width 0.1524)
				(type default)
			)
			(layer "F.SilkS")
		)
		(fp_rect
			(start -0.508 0.9398)
			(end 0.508 -0.9398)
			(stroke
				(width 0)
				(type default)
			)
			(fill no)
			(layer "F.CrtYd")
		)
		(fp_rect
			(start -0.508 0.9398)
			(end 0.508 -0.9398)
			(stroke
				(width 0)
				(type default)
			)
			(fill no)
			(layer "F.Fab")
		)
		(pad "1" smd custom
			(at 0 -0.4445)
			(size 0.1397 0.1397)
			(layers "F.Cu" "F.Mask" "F.Paste")
			(net "P3V3_STBY_A")
			(options
				(clearance outline)
				(anchor circle)
			)
			(primitives
				(gr_poly
					(pts
						(arc
							(start -0.1778 -0.2794)
							(mid -0.249642 -0.249642)
							(end -0.2794 -0.1778)
						)
						(arc
							(start -0.2794 0.1778)
							(mid -0.249642 0.249642)
							(end -0.1778 0.2794)
						)
						(arc
							(start 0.1778 0.2794)
							(mid 0.249642 0.249642)
							(end 0.2794 0.1778)
						)
						(arc
							(start 0.2794 -0.1778)
							(mid 0.249642 -0.249642)
							(end 0.1778 -0.2794)
						)
					)
					(width 0)
					(fill yes)
				)
			)
		)
		(pad "2" smd custom
			(at 0 0.4445)
			(size 0.1397 0.1397)
			(layers "F.Cu" "F.Mask" "F.Paste")
			(net "IO_EXP1_HDD_FAULT_A0")
			(options
				(clearance outline)
				(anchor circle)
			)
			(primitives
				(gr_poly
					(pts
						(arc
							(start -0.1778 -0.2794)
							(mid -0.249642 -0.249642)
							(end -0.2794 -0.1778)
						)
						(arc
							(start -0.2794 0.1778)
							(mid -0.249642 0.249642)
							(end -0.1778 0.2794)
						)
						(arc
							(start 0.1778 0.2794)
							(mid 0.249642 0.249642)
							(end 0.2794 0.1778)
						)
						(arc
							(start 0.2794 -0.1778)
							(mid 0.249642 -0.249642)
							(end 0.1778 -0.2794)
						)
					)
					(width 0)
					(fill yes)
				)
			)
		)
	)
	(footprint ""
		(layer "F.Cu")
		(at 180.7464 -46.014894 -90)
		(property "Reference" "R805"
			(at 0 0 270)
			(layer "F.SilkS")
			(hide yes)
			(effects
				(font
					(size 1.27 1.27)
				)
			)
		)
		(property "Value" "1KR2F-3-GP"
			(at 0.064008 -3.993896 270)
			(unlocked yes)
			(layer "F.Fab")
			(hide yes)
			(effects
				(font
					(size 1.016 1.016)
					(thickness 0.1524)
				)
			)
		)
		(property "Device Type" "R402H16"
			(at 0.064008 -5.517896 270)
			(unlocked yes)
			(layer "F.Fab")
			(hide yes)
			(effects
				(font
					(size 1.016 1.016)
					(thickness 0.1524)
				)
			)
		)
		(duplicate_pad_numbers_are_jumpers no)
		(fp_line
			(start -0.508 -0.9398)
			(end -0.508 0.9398)
			(stroke
				(width 0.1524)
				(type default)
			)
			(layer "F.SilkS")
		)
		(fp_line
			(start 0.508 -0.9398)
			(end -0.508 -0.9398)
			(stroke
				(width 0.1524)
				(type default)
			)
			(layer "F.SilkS")
		)
		(fp_rect
			(start -0.508 0.9398)
			(end 0.508 -0.9398)
			(stroke
				(width 0)
				(type default)
			)
			(fill no)
			(layer "F.CrtYd")
		)
		(fp_rect
			(start -0.508 0.9398)
			(end 0.508 -0.9398)
			(stroke
				(width 0)
				(type default)
			)
			(fill no)
			(layer "F.Fab")
		)
		(pad "1" smd custom
			(at 0 -0.4445 270)
			(size 0.1397 0.1397)
			(layers "F.Cu" "F.Mask" "F.Paste")
			(net "P3V3_STBY_A")
			(options
				(clearance outline)
				(anchor circle)
			)
			(primitives
				(gr_poly
					(pts
						(arc
							(start -0.1778 -0.2794)
							(mid -0.249642 -0.249642)
							(end -0.2794 -0.1778)
						)
						(arc
							(start -0.2794 0.1778)
							(mid -0.249642 0.249642)
							(end -0.1778 0.2794)
						)
						(arc
							(start 0.1778 0.2794)
							(mid 0.249642 0.249642)
							(end 0.2794 0.1778)
						)
						(arc
							(start 0.2794 -0.1778)
							(mid 0.249642 -0.249642)
							(end 0.1778 -0.2794)
						)
					)
					(width 0)
					(fill yes)
				)
			)
		)
		(pad "2" smd custom
			(at 0 0.4445 270)
			(size 0.1397 0.1397)
			(layers "F.Cu" "F.Mask" "F.Paste")
			(net "SW_PWR_R_HDD29")
			(options
				(clearance outline)
				(anchor circle)
			)
			(primitives
				(gr_poly
					(pts
						(arc
							(start -0.1778 -0.2794)
							(mid -0.249642 -0.249642)
							(end -0.2794 -0.1778)
						)
						(arc
							(start -0.2794 0.1778)
							(mid -0.249642 0.249642)
							(end -0.1778 0.2794)
						)
						(arc
							(start 0.1778 0.2794)
							(mid 0.249642 0.249642)
							(end 0.2794 0.1778)
						)
						(arc
							(start 0.2794 -0.1778)
							(mid 0.249642 -0.249642)
							(end 0.1778 -0.2794)
						)
					)
					(width 0)
					(fill yes)
				)
			)
		)
	)
	(footprint ""
		(layer "F.Cu")
		(at 336.931 -160.735518 180)
		(property "Reference" "R558"
			(at 0 0 180)
			(layer "F.SilkS")
			(hide yes)
			(effects
				(font
					(size 1.27 1.27)
				)
			)
		)
		(property "Value" "4K7R2J-2-GP"
			(at 0.064008 -3.993896 180)
			(unlocked yes)
			(layer "F.Fab")
			(hide yes)
			(effects
				(font
					(size 1.016 1.016)
					(thickness 0.1524)
				)
			)
		)
		(property "Device Type" "R402H16"
			(at 0.064008 -5.517896 180)
			(unlocked yes)
			(layer "F.Fab")
			(hide yes)
			(effects
				(font
					(size 1.016 1.016)
					(thickness 0.1524)
				)
			)
		)
		(duplicate_pad_numbers_are_jumpers no)
		(fp_line
			(start 0.508 -0.9398)
			(end -0.508 -0.9398)
			(stroke
				(width 0.1524)
				(type default)
			)
			(layer "F.SilkS")
		)
		(fp_line
			(start -0.508 -0.9398)
			(end -0.508 0.9398)
			(stroke
				(width 0.1524)
				(type default)
			)
			(layer "F.SilkS")
		)
		(fp_rect
			(start -0.508 0.9398)
			(end 0.508 -0.9398)
			(stroke
				(width 0)
				(type default)
			)
			(fill no)
			(layer "F.CrtYd")
		)
		(fp_rect
			(start -0.508 0.9398)
			(end 0.508 -0.9398)
			(stroke
				(width 0)
				(type default)
			)
			(fill no)
			(layer "F.Fab")
		)
		(pad "1" smd custom
			(at 0 -0.4445 180)
			(size 0.1397 0.1397)
			(layers "F.Cu" "F.Mask" "F.Paste")
			(net "P12V_A")
			(options
				(clearance outline)
				(anchor circle)
			)
			(primitives
				(gr_poly
					(pts
						(arc
							(start -0.1778 -0.2794)
							(mid -0.249642 -0.249642)
							(end -0.2794 -0.1778)
						)
						(arc
							(start -0.2794 0.1778)
							(mid -0.249642 0.249642)
							(end -0.1778 0.2794)
						)
						(arc
							(start 0.1778 0.2794)
							(mid 0.249642 0.249642)
							(end 0.2794 0.1778)
						)
						(arc
							(start 0.2794 -0.1778)
							(mid 0.249642 -0.249642)
							(end 0.1778 -0.2794)
						)
					)
					(width 0)
					(fill yes)
				)
			)
		)
		(pad "2" smd custom
			(at 0 0.4445 180)
			(size 0.1397 0.1397)
			(layers "F.Cu" "F.Mask" "F.Paste")
			(net "SW_HDD_R18")
			(options
				(clearance outline)
				(anchor circle)
			)
			(primitives
				(gr_poly
					(pts
						(arc
							(start -0.1778 -0.2794)
							(mid -0.249642 -0.249642)
							(end -0.2794 -0.1778)
						)
						(arc
							(start -0.2794 0.1778)
							(mid -0.249642 0.249642)
							(end -0.1778 0.2794)
						)
						(arc
							(start 0.1778 0.2794)
							(mid 0.249642 0.249642)
							(end 0.2794 0.1778)
						)
						(arc
							(start 0.2794 -0.1778)
							(mid 0.249642 -0.249642)
							(end 0.1778 -0.2794)
						)
					)
					(width 0)
					(fill yes)
				)
			)
		)
	)
)
